# S9S_MB_2U (Grand Teton) — schematic netlist excerpt (pin names and nets, part order shuffled) for the footprints in the layout excerpt that follows; sources: Cadence DE-HDL packaged netlist, KiCad conversion of 03242023_DA0F0TMBIJ0_F0T_Motherboard_J_brd_V01_OCP.brd

J17  SCONN288_ADR50017P130CC  SCONN288_ADR50017-P130CC IO  pkg DDR288S_1-1VXB  page 98
  VIN_BULK0  = P12V_S3_AUX_CPU1_NVDIMM
  RFU0  = TP_CHA_CPU1_DIMM1_FRU_0
  VIN_MGMT  = P3V3_AUX
  HSCL  = I3C_SPD_DDRABCD_CPU1_LVC1_SCL_R
  HSDA  = I3C_SPD_DDRABCD_CPU1_LVC1_SDA
  VSS0  = GND
  DQ0_A  = M_A_CPU1_SA_DQ<0>
  VSS1  = GND
  DQ1_A  = M_A_CPU1_SA_DQ<1>
  VSS2  = GND
  DQS0_A_T  = M_A_CPU1_SA_DQS_DP<0>
  DQS0_A_C  = M_A_CPU1_SA_DQS_DN<0>
  VSS3  = GND
  DQ4_A  = M_A_CPU1_SA_DQ<4>
  VSS4  = GND
  DQ5_A  = M_A_CPU1_SA_DQ<5>
  VSS5  = GND
  DQ8_A  = M_A_CPU1_SA_DQ<8>
  VSS6  = GND
  DQ9_A  = M_A_CPU1_SA_DQ<9>
  VSS7  = GND
  DQS1_A_T  = M_A_CPU1_SA_DQS_DP<1>
  DQS1_A_C  = M_A_CPU1_SA_DQS_DN<1>
  VSS8  = GND
  DQ12_A  = M_A_CPU1_SA_DQ<12>
  VSS9  = GND
  DQ13_A  = M_A_CPU1_SA_DQ<13>
  VSS10  = GND
  DQ16_A  = M_A_CPU1_SA_DQ<16>
  VSS11  = GND
  DQ17_A  = M_A_CPU1_SA_DQ<17>
  VSS12  = GND
  DQS2_A_T  = M_A_CPU1_SA_DQS_DP<2>
  DQS2_A_C  = M_A_CPU1_SA_DQS_DN<2>
  VSS13  = GND
  DQ20_A  = M_A_CPU1_SA_DQ<20>
  VSS14  = GND
  DQ21_A  = M_A_CPU1_SA_DQ<21>
  VSS15  = GND
  DQ24_A  = M_A_CPU1_SA_DQ<24>
  VSS16  = GND
  DQ25_A  = M_A_CPU1_SA_DQ<25>
  VSS17  = GND
  DQS3_A_T  = M_A_CPU1_SA_DQS_DP<3>
  DQS3_A_C  = M_A_CPU1_SA_DQS_DN<3>
  VSS18  = GND
  DQ28_A  = M_A_CPU1_SA_DQ<28>
  VSS19  = GND
  DQ29_A  = M_A_CPU1_SA_DQ<29>
  VSS20  = GND
  CB0_A  = M_A_CPU1_SA_CB<0>
  VSS21  = GND
  CB1_A  = M_A_CPU1_SA_CB<1>
  VSS22  = GND
  DQS4_A_T  = M_A_CPU1_SA_DQS_DP<4>
  DQS4_A_C  = M_A_CPU1_SA_DQS_DN<4>
  VSS23  = GND
  CB4_A  = M_A_CPU1_SA_CB<4>
  VSS24  = GND
  CB5_A  = M_A_CPU1_SA_CB<5>
  VSS25  = GND
  ALERT_N  = M_A_CPU1_ALERT_N
  VSS26  = GND
  CS0_A_N  = M_A_CPU1_SA_CS_N<0>
  VSS27  = GND
  CA0_A  = M_A_CPU1_SA_CA<0>
  VSS28  = GND
  CA2_A  = M_A_CPU1_SA_CA<2>
  VSS29  = GND
  CA4_A  = M_A_CPU1_SA_CA<4>
  VSS30  = GND
  CA6_A  = M_A_CPU1_SA_CA<6>
  VSS31  = GND
  PAR_A  = M_A_CPU1_SA_PAR
  VSS32  = GND
  CA0_B  = M_A_CPU1_SB_CA<0>
  VSS33  = GND
  CA2_B  = M_A_CPU1_SB_CA<2>
  VSS34  = GND
  CA4_B  = M_A_CPU1_SB_CA<4>
  VSS35  = GND
  CA6_B  = M_A_CPU1_SB_CA<6>
  VSS36  = GND
  CS0_B_N  = M_A_CPU1_SB_CS_N<0>
  VSS37  = GND
  \lbd||rsp_a_n\  = M_A_CPU1_SA_RSP<0>
  \lbs||rsp_b_n\  = M_A_CPU1_SB_RSP<0>
  VSS38  = GND
  CB4_B  = M_A_CPU1_SB_CB<4>
  VSS39  = GND
  CB5_B  = M_A_CPU1_SB_CB<5>
  VSS40  = GND
  \dqs9_b_t||tdqs9_b_t||dbi4_b_n\  = M_A_CPU1_SB_DQS_DP<9>
  \dqs9_b_c||tdqs9_b_c\  = M_A_CPU1_SB_DQS_DN<9>
  VSS41  = GND
  CB0_B  = M_A_CPU1_SB_CB<0>
  VSS42  = GND
  CB1_B  = M_A_CPU1_SB_CB<1>
  VSS43  = GND
  DQ0_B  = M_A_CPU1_SB_DQ<0>
  VSS44  = GND
  DQ1_B  = M_A_CPU1_SB_DQ<1>
  VSS45  = GND
  DQS0_B_T  = M_A_CPU1_SB_DQS_DP<0>
  DQS0_B_C  = M_A_CPU1_SB_DQS_DN<0>
  VSS46  = GND
  DQ4_B  = M_A_CPU1_SB_DQ<4>
  VSS47  = GND
  DQ5_B  = M_A_CPU1_SB_DQ<5>
  VSS48  = GND
  DQ8_B  = M_A_CPU1_SB_DQ<8>
  VSS49  = GND
  DQ9_B  = M_A_CPU1_SB_DQ<9>
  VSS50  = GND
  DQS1_B_T  = M_A_CPU1_SB_DQS_DP<1>
  DQS1_B_C  = M_A_CPU1_SB_DQS_DN<1>
  VSS51  = GND
  DQ12_B  = M_A_CPU1_SB_DQ<12>
  VSS52  = GND
  DQ13_B  = M_A_CPU1_SB_DQ<13>
  VSS53  = GND
  DQ16_B  = M_A_CPU1_SB_DQ<16>
  VSS54  = GND
  DQ17_B  = M_A_CPU1_SB_DQ<17>
  VSS55  = GND
  DQS2_B_T  = M_A_CPU1_SB_DQS_DP<2>
  DQS2_B_C  = M_A_CPU1_SB_DQS_DN<2>
  VSS56  = GND
  DQ20_B  = M_A_CPU1_SB_DQ<20>
  VSS57  = GND
  DQ21_B  = M_A_CPU1_SB_DQ<21>
  VSS58  = GND
  DQ24_B  = M_A_CPU1_SB_DQ<24>
  VSS59  = GND
  DQ25_B  = M_A_CPU1_SB_DQ<25>
  VSS60  = GND
  DQS3_B_T  = M_A_CPU1_SB_DQS_DP<3>
  DQS3_B_C  = M_A_CPU1_SB_DQS_DN<3>
  VSS61  = GND
  DQ28_B  = M_A_CPU1_SB_DQ<28>
  VSS62  = GND
  DQ29_B  = M_A_CPU1_SB_DQ<29>
  VSS63  = GND
  RFU1  = TP_CHA_CPU1_DIMM1_FRU_1
  VIN_BULK1  = P12V_S3_AUX_CPU1_NVDIMM
  VIN_BULK2  = P12V_S3_AUX_CPU1_NVDIMM
  \pwr_good||fail_n\  = PWRGD_CHA_CPU1_DIMM1
  HSA  = PD_CHA_CPU1_DIMM1_SAA
  RFU2  = TP_CHA_CPU1_DIMM1_FRU_2
  RFU3  = TP_CHA_CPU1_DIMM1_FRU_3
  VSS64  = GND
  DQ2_A  = M_A_CPU1_SA_DQ<2>
  VSS65  = GND
  DQ3_A  = M_A_CPU1_SA_DQ<3>
  VSS66  = GND
  \dqs5_a_c||tdqs5_a_c||dqs5_a_t||tdqs5_a_t\  = M_A_CPU1_SA_DQS_DN<5>
  \dqs5_a_t||tdqs5_a_t\  = M_A_CPU1_SA_DQS_DP<5>
  VSS67  = GND
  DQ6_A  = M_A_CPU1_SA_DQ<6>
  VSS68  = GND
  DQ7_A  = M_A_CPU1_SA_DQ<7>
  VSS69  = GND
  DQ10_A  = M_A_CPU1_SA_DQ<10>
  VSS70  = GND
  DQ11_A  = M_A_CPU1_SA_DQ<11>
  VSS71  = GND
  \dqs6_a_c||tdqs6_a_c||dqs6_a_t||tdqs6_a_t\  = M_A_CPU1_SA_DQS_DN<6>
  \dqs6_a_t||tdqs6_a_t\  = M_A_CPU1_SA_DQS_DP<6>
  VSS72  = GND
  DQ14_A  = M_A_CPU1_SA_DQ<14>
  VSS73  = GND
  DQ15_A  = M_A_CPU1_SA_DQ<15>
  VSS74  = GND
  DQ18_A  = M_A_CPU1_SA_DQ<18>
  VSS75  = GND
  DQ19_A  = M_A_CPU1_SA_DQ<19>
  VSS76  = GND
  \dqs7_a_c||tdqs7_a_c\  = M_A_CPU1_SA_DQS_DN<7>
  \dqs7_a_t||tdqs7_a_t\  = M_A_CPU1_SA_DQS_DP<7>
  VSS77  = GND
  DQ22_A  = M_A_CPU1_SA_DQ<22>
  VSS78  = GND
  DQ23_A  = M_A_CPU1_SA_DQ<23>
  VSS79  = GND
  DQ26_A  = M_A_CPU1_SA_DQ<26>
  VSS80  = GND
  DQ27_A  = M_A_CPU1_SA_DQ<27>
  VSS81  = GND
  \dqs8_a_c||tdqs8_a_c\  = M_A_CPU1_SA_DQS_DN<8>
  \dqs8_a_t||tdqs8_a_t\  = M_A_CPU1_SA_DQS_DP<8>
  VSS82  = GND
  DQ30_A  = M_A_CPU1_SA_DQ<30>
  VSS83  = GND
  DQ31_A  = M_A_CPU1_SA_DQ<31>
  VSS84  = GND
  CB2_A  = M_A_CPU1_SA_CB<2>
  VSS85  = GND
  CB3_A  = M_A_CPU1_SA_CB<3>
  VSS86  = GND
  \dqs9_a_c||tdqs9_a_c\  = M_A_CPU1_SA_DQS_DN<9>
  \dqs9_a_t||tdqs9_a_t\  = M_A_CPU1_SA_DQS_DP<9>
  VSS87  = GND
  CB6_A  = M_A_CPU1_SA_CB<6>
  VSS88  = GND
  CB7_A  = M_A_CPU1_SA_CB<7>
  VSS89  = GND
  RESET_N  = RST_M_AB_CPU1_FPGA_N
  VSS90  = GND
  CS1_A_N  = M_A_CPU1_SA_CS_N<1>
  VSS91  = GND
  CA1_A  = M_A_CPU1_SA_CA<1>
  VSS92  = GND
  CA3_A  = M_A_CPU1_SA_CA<3>
  VSS93  = GND
  CA5_A  = M_A_CPU1_SA_CA<5>
  VSS94  = GND
  CK_T  = M_A_CPU1_CLK_DP<0>
  CK_C  = M_A_CPU1_CLK_DN<0>
  VSS95  = GND
  RFU4  = TP_CHA_CPU1_DIMM1_FRU_4
  CA1_B  = M_A_CPU1_SB_CA<1>
  VSS96  = GND
  CA3_B  = M_A_CPU1_SB_CA<3>
  VSS97  = GND
  CA5_B  = M_A_CPU1_SB_CA<5>
  VSS98  = GND
  PAR_B  = M_A_CPU1_SB_PAR
  VSS99  = GND
  CS1_B_N  = M_A_CPU1_SB_CS_N<1>
  VSS100  = GND
  RFU5  = TP_CHA_CPU1_DIMM1_FRU_5
  RFU6  = TP_CHA_CPU1_DIMM1_FRU_6
  VSS101  = GND
  CB6_B  = M_A_CPU1_SB_CB<6>
  VSS102  = GND
  CB7_B  = M_A_CPU1_SB_CB<7>
  VSS103  = GND
  DQS4_B_C  = M_A_CPU1_SB_DQS_DN<4>
  DQS4_B_T  = M_A_CPU1_SB_DQS_DP<4>
  VSS104  = GND
  CB2_B  = M_A_CPU1_SB_CB<2>
  VSS105  = GND
  CB3_B  = M_A_CPU1_SB_CB<3>
  VSS106  = GND
  DQ2_B  = M_A_CPU1_SB_DQ<2>
  VSS107  = GND
  DQ3_B  = M_A_CPU1_SB_DQ<3>
  VSS108  = GND
  \dqs5_b_c||tdqs5_b_c\  = M_A_CPU1_SB_DQS_DN<5>
  \dqs5_b_t||tdqs5_b_t\  = M_A_CPU1_SB_DQS_DP<5>
  VSS109  = GND
  DQ6_B  = M_A_CPU1_SB_DQ<6>
  VSS110  = GND
  DQ7_B  = M_A_CPU1_SB_DQ<7>
  VSS111  = GND
  DQ10_B  = M_A_CPU1_SB_DQ<10>
  VSS112  = GND
  DQ11_B  = M_A_CPU1_SB_DQ<11>
  VSS113  = GND
  \dqs6_b_c||tdqs6_b_c\  = M_A_CPU1_SB_DQS_DN<6>
  \dqs6_b_t||tdqs6_b_t\  = M_A_CPU1_SB_DQS_DP<6>
  VSS114  = GND
  DQ14_B  = M_A_CPU1_SB_DQ<14>
  VSS115  = GND
  DQ15_B  = M_A_CPU1_SB_DQ<15>
  VSS116  = GND
  DQ18_B  = M_A_CPU1_SB_DQ<18>
  VSS117  = GND
  DQ19_B  = M_A_CPU1_SB_DQ<19>
  VSS118  = GND
  \dqs7_b_c||tdqs7_b_c\  = M_A_CPU1_SB_DQS_DN<7>
  \dqs7_b_t||tdqs7_b_t\  = M_A_CPU1_SB_DQS_DP<7>
  VSS119  = GND
  DQ22_B  = M_A_CPU1_SB_DQ<22>
  VSS120  = GND
  DQ23_B  = M_A_CPU1_SB_DQ<23>
  VSS121  = GND
  DQ26_B  = M_A_CPU1_SB_DQ<26>
  VSS122  = GND
  DQ27_B  = M_A_CPU1_SB_DQ<27>
  VSS123  = GND
  \dqs8_b_c||tdqs8_b_c\  = M_A_CPU1_SB_DQS_DN<8>
  \dqs8_b_t||tdqs8_b_t\  = M_A_CPU1_SB_DQS_DP<8>
  VSS124  = GND
  DQ30_B  = M_A_CPU1_SB_DQ<30>
  VSS125  = GND
  DQ31_B  = M_A_CPU1_SB_DQ<31>
  VSS126  = GND
  G1  = GND
  G2  = GND
  G3  = GND

(kicad_pcb
	(version 20260206)
	(generator "pcbnew")
	(generator_version "10.0")
	(general
		(thickness 1.6)
		(legacy_teardrops no)
	)
	(paper "A4")
	(title_block
		(title "03242023_DA0F0TMBIJ0_F0T_Motherboard_J_brd_V01_OCP.brd")
		(comment 1 "Grand Teton / footprint 1335 of 6105 (J17), pads 46-91 of 291")
	)
	(layers
		(0 "F.Cu" signal "TOP")
		(4 "In1.Cu" signal "GND")
		(6 "In2.Cu" signal "IN1")
		(8 "In3.Cu" signal "GND1")
		(10 "In4.Cu" signal "IN2")
		(12 "In5.Cu" signal "GND2")
		(14 "In6.Cu" signal "IN3")
		(16 "In7.Cu" signal "GND3")
		(18 "In8.Cu" signal "VCC")
		(20 "In9.Cu" signal "VCC1")
		(22 "In10.Cu" signal "GND4")
		(24 "In11.Cu" signal "IN4")
		(26 "In12.Cu" signal "GND5")
		(28 "In13.Cu" signal "IN5")
		(30 "In14.Cu" signal "GND6")
		(32 "In15.Cu" signal "IN6")
		(34 "In16.Cu" signal "GND7")
		(2 "B.Cu" signal "BOTTOM")
		(9 "F.Adhes" user "F.Adhesive")
		(11 "B.Adhes" user "B.Adhesive")
		(13 "F.Paste" user "Package Geometry/Pastemask Top")
		(15 "B.Paste" user "Package Geometry/Pastemask Bottom")
		(5 "F.SilkS" user "Ref Des/Silkscreen Top")
		(7 "B.SilkS" user "Ref Des/Silkscreen Bottom")
		(1 "F.Mask" user "Board Geometry/Soldermask Top")
		(3 "B.Mask" user "Board Geometry/Soldermask Bottom")
		(17 "Dwgs.User" user "User.Drawings")
		(19 "Cmts.User" user "User.Comments")
		(21 "Eco1.User" user "User.Eco1")
		(23 "Eco2.User" user "User.Eco2")
		(25 "Edge.Cuts" user "Board Geometry/Outline")
		(27 "Margin" user)
		(31 "F.CrtYd" user "Package Geometry/Place Bound Top")
		(29 "B.CrtYd" user "Package Geometry/Place Bound Bottom")
		(35 "F.Fab" user "Ref Des/Assembly Top")
		(33 "B.Fab" user "Ref Des/Assembly Bottom")
	)
	(footprint ""
		(layer "F.Cu")
		(at 55.45328 -258.091686)
		(property "Reference" "J17"
			(at -0.178562 -81.717134 0)
			(unlocked yes)
			(layer "F.SilkS")
			(effects
				(font
					(size 0.7874 0.5842)
					(thickness 0.1524)
				)
				(justify left)
			)
		)
		(property "Value" ""
			(at 0 0 0)
			(layer "F.Fab")
			(effects
				(font
					(size 1.27 1.27)
				)
			)
		)
		(duplicate_pad_numbers_are_jumpers no)
		(pad "46" smd rect
			(at -2.050034 -25.07488 270)
			(size 0.519938 1.4986)
			(layers "F.Cu" "F.Mask" "F.Paste")
			(net "GND")
		)
		(pad "47" smd rect
			(at -2.050034 -24.224996 270)
			(size 0.519938 1.4986)
			(layers "F.Cu" "F.Mask" "F.Paste")
			(net "M_A_CPU1_SA_DQ<28>")
		)
		(pad "48" smd rect
			(at -2.050034 -23.375112 270)
			(size 0.519938 1.4986)
			(layers "F.Cu" "F.Mask" "F.Paste")
			(net "GND")
		)
		(pad "49" smd rect
			(at -2.050034 -22.524974 270)
			(size 0.519938 1.4986)
			(layers "F.Cu" "F.Mask" "F.Paste")
			(net "M_A_CPU1_SA_DQ<29>")
		)
		(pad "50" smd rect
			(at -2.050034 -21.67509 270)
			(size 0.519938 1.4986)
			(layers "F.Cu" "F.Mask" "F.Paste")
			(net "GND")
		)
		(pad "51" smd rect
			(at -2.050034 -20.824952 270)
			(size 0.519938 1.4986)
			(layers "F.Cu" "F.Mask" "F.Paste")
			(net "M_A_CPU1_SA_CB<0>")
		)
		(pad "52" smd rect
			(at -2.050034 -19.975068 270)
			(size 0.519938 1.4986)
			(layers "F.Cu" "F.Mask" "F.Paste")
			(net "GND")
		)
		(pad "53" smd rect
			(at -2.050034 -19.12493 270)
			(size 0.519938 1.4986)
			(layers "F.Cu" "F.Mask" "F.Paste")
			(net "M_A_CPU1_SA_CB<1>")
		)
		(pad "54" smd rect
			(at -2.050034 -18.275046 270)
			(size 0.519938 1.4986)
			(layers "F.Cu" "F.Mask" "F.Paste")
			(net "GND")
		)
		(pad "55" smd rect
			(at -2.050034 -17.424908 270)
			(size 0.519938 1.4986)
			(layers "F.Cu" "F.Mask" "F.Paste")
			(net "M_A_CPU1_SA_DQS_DP<4>")
		)
		(pad "56" smd rect
			(at -2.050034 -16.575024 270)
			(size 0.519938 1.4986)
			(layers "F.Cu" "F.Mask" "F.Paste")
			(net "M_A_CPU1_SA_DQS_DN<4>")
		)
		(pad "57" smd rect
			(at -2.050034 -15.724886 270)
			(size 0.519938 1.4986)
			(layers "F.Cu" "F.Mask" "F.Paste")
			(net "GND")
		)
		(pad "58" smd rect
			(at -2.050034 -14.875002 270)
			(size 0.519938 1.4986)
			(layers "F.Cu" "F.Mask" "F.Paste")
			(net "M_A_CPU1_SA_CB<4>")
		)
		(pad "59" smd rect
			(at -2.050034 -14.025118 270)
			(size 0.519938 1.4986)
			(layers "F.Cu" "F.Mask" "F.Paste")
			(net "GND")
		)
		(pad "60" smd rect
			(at -2.050034 -13.17498 270)
			(size 0.519938 1.4986)
			(layers "F.Cu" "F.Mask" "F.Paste")
			(net "M_A_CPU1_SA_CB<5>")
		)
		(pad "61" smd rect
			(at -2.050034 -12.325096 270)
			(size 0.519938 1.4986)
			(layers "F.Cu" "F.Mask" "F.Paste")
			(net "GND")
		)
		(pad "62" smd rect
			(at -2.050034 -11.474958 270)
			(size 0.519938 1.4986)
			(layers "F.Cu" "F.Mask" "F.Paste")
			(net "M_A_CPU1_ALERT_N")
		)
		(pad "63" smd rect
			(at -2.050034 -10.625074 270)
			(size 0.519938 1.4986)
			(layers "F.Cu" "F.Mask" "F.Paste")
			(net "GND")
		)
		(pad "64" smd rect
			(at -2.050034 -9.774936 270)
			(size 0.519938 1.4986)
			(layers "F.Cu" "F.Mask" "F.Paste")
			(net "M_A_CPU1_SA_CS_N<0>")
		)
		(pad "65" smd rect
			(at -2.050034 -8.925052 270)
			(size 0.519938 1.4986)
			(layers "F.Cu" "F.Mask" "F.Paste")
			(net "GND")
		)
		(pad "66" smd rect
			(at -2.050034 -8.074914 270)
			(size 0.519938 1.4986)
			(layers "F.Cu" "F.Mask" "F.Paste")
			(net "M_A_CPU1_SA_CA<0>")
		)
		(pad "67" smd rect
			(at -2.050034 -7.22503 270)
			(size 0.519938 1.4986)
			(layers "F.Cu" "F.Mask" "F.Paste")
			(net "GND")
		)
		(pad "68" smd rect
			(at -2.050034 -6.374892 270)
			(size 0.519938 1.4986)
			(layers "F.Cu" "F.Mask" "F.Paste")
			(net "M_A_CPU1_SA_CA<2>")
		)
		(pad "69" smd rect
			(at -2.050034 -5.525008 270)
			(size 0.519938 1.4986)
			(layers "F.Cu" "F.Mask" "F.Paste")
			(net "GND")
		)
		(pad "70" smd rect
			(at -2.050034 -4.675124 270)
			(size 0.519938 1.4986)
			(layers "F.Cu" "F.Mask" "F.Paste")
			(net "M_A_CPU1_SA_CA<4>")
		)
		(pad "71" smd rect
			(at -2.050034 -3.824986 270)
			(size 0.519938 1.4986)
			(layers "F.Cu" "F.Mask" "F.Paste")
			(net "GND")
		)
		(pad "72" smd rect
			(at -2.050034 -2.975102 270)
			(size 0.519938 1.4986)
			(layers "F.Cu" "F.Mask" "F.Paste")
			(net "M_A_CPU1_SA_CA<6>")
		)
		(pad "73" smd rect
			(at -2.050034 -2.124964 270)
			(size 0.519938 1.4986)
			(layers "F.Cu" "F.Mask" "F.Paste")
			(net "GND")
		)
		(pad "74" smd rect
			(at -2.050034 -1.27508 270)
			(size 0.519938 1.4986)
			(layers "F.Cu" "F.Mask" "F.Paste")
			(net "M_A_CPU1_SA_PAR")
		)
		(pad "75" smd rect
			(at -2.050034 -0.424942 270)
			(size 0.519938 1.4986)
			(layers "F.Cu" "F.Mask" "F.Paste")
			(net "GND")
		)
		(pad "76" smd rect
			(at -2.050034 5.525008 270)
			(size 0.519938 1.4986)
			(layers "F.Cu" "F.Mask" "F.Paste")
			(net "M_A_CPU1_SB_CA<0>")
		)
		(pad "77" smd rect
			(at -2.050034 6.374892 270)
			(size 0.519938 1.4986)
			(layers "F.Cu" "F.Mask" "F.Paste")
			(net "GND")
		)
		(pad "78" smd rect
			(at -2.050034 7.22503 270)
			(size 0.519938 1.4986)
			(layers "F.Cu" "F.Mask" "F.Paste")
			(net "M_A_CPU1_SB_CA<2>")
		)
		(pad "79" smd rect
			(at -2.050034 8.074914 270)
			(size 0.519938 1.4986)
			(layers "F.Cu" "F.Mask" "F.Paste")
			(net "GND")
		)
		(pad "80" smd rect
			(at -2.050034 8.925052 270)
			(size 0.519938 1.4986)
			(layers "F.Cu" "F.Mask" "F.Paste")
			(net "M_A_CPU1_SB_CA<4>")
		)
		(pad "81" smd rect
			(at -2.050034 9.774936 270)
			(size 0.519938 1.4986)
			(layers "F.Cu" "F.Mask" "F.Paste")
			(net "GND")
		)
		(pad "82" smd rect
			(at -2.050034 10.625074 270)
			(size 0.519938 1.4986)
			(layers "F.Cu" "F.Mask" "F.Paste")
			(net "M_A_CPU1_SB_CA<6>")
		)
		(pad "83" smd rect
			(at -2.050034 11.474958 270)
			(size 0.519938 1.4986)
			(layers "F.Cu" "F.Mask" "F.Paste")
			(net "GND")
		)
		(pad "84" smd rect
			(at -2.050034 12.325096 270)
			(size 0.519938 1.4986)
			(layers "F.Cu" "F.Mask" "F.Paste")
			(net "M_A_CPU1_SB_CS_N<0>")
		)
		(pad "85" smd rect
			(at -2.050034 13.17498 270)
			(size 0.519938 1.4986)
			(layers "F.Cu" "F.Mask" "F.Paste")
			(net "GND")
		)
		(pad "86" smd rect
			(at -2.050034 14.025118 270)
			(size 0.519938 1.4986)
			(layers "F.Cu" "F.Mask" "F.Paste")
			(net "M_A_CPU1_SA_RSP<0>")
		)
		(pad "87" smd rect
			(at -2.050034 14.875002 270)
			(size 0.519938 1.4986)
			(layers "F.Cu" "F.Mask" "F.Paste")
			(net "M_A_CPU1_SB_RSP<0>")
		)
		(pad "88" smd rect
			(at -2.050034 15.724886 270)
			(size 0.519938 1.4986)
			(layers "F.Cu" "F.Mask" "F.Paste")
			(net "GND")
		)
		(pad "89" smd rect
			(at -2.050034 16.575024 270)
			(size 0.519938 1.4986)
			(layers "F.Cu" "F.Mask" "F.Paste")
			(net "M_A_CPU1_SB_CB<4>")
		)
		(pad "90" smd rect
			(at -2.050034 17.424908 270)
			(size 0.519938 1.4986)
			(layers "F.Cu" "F.Mask" "F.Paste")
			(net "GND")
		)
		(pad "91" smd rect
			(at -2.050034 18.275046 270)
			(size 0.519938 1.4986)
			(layers "F.Cu" "F.Mask" "F.Paste")
			(net "M_A_CPU1_SB_CB<5>")
		)
	)
)
